(kicad_pcb
	(version 20260206)
	(generator "pcbnew")
	(generator_version "10.0")
	(general
		(thickness 1.6)
		(legacy_teardrops no)
	)
	(paper "A4")
	(title_block
		(title "dpb — 14545-sa.0730WZS0815.brd")
		(comment 1 "Honey Badger (Wiwynn) / footprints 851-856 of 1066")
	)
	(layers
		(0 "F.Cu" signal "TOP")
		(4 "In1.Cu" signal "L2GND")
		(6 "In2.Cu" signal "L3")
		(8 "In3.Cu" signal "L4VCC")
		(10 "In4.Cu" signal "L5VCC")
		(12 "In5.Cu" signal "L6")
		(14 "In6.Cu" signal "L7GND")
		(2 "B.Cu" signal "BOTTOM")
		(9 "F.Adhes" user "F.Adhesive")
		(11 "B.Adhes" user "B.Adhesive")
		(13 "F.Paste" user "Package Geometry/Pastemask Top")
		(15 "B.Paste" user "Package Geometry/Pastemask Bottom")
		(5 "F.SilkS" user "Ref Des/Silkscreen Top")
		(7 "B.SilkS" user "Ref Des/Silkscreen Bottom")
		(1 "F.Mask" user "Board Geometry/Soldermask Top")
		(3 "B.Mask" user "Board Geometry/Soldermask Bottom")
		(17 "Dwgs.User" user "User.Drawings")
		(19 "Cmts.User" user "User.Comments")
		(21 "Eco1.User" user "User.Eco1")
		(23 "Eco2.User" user "User.Eco2")
		(25 "Edge.Cuts" user "Board Geometry/Outline")
		(27 "Margin" user)
		(31 "F.CrtYd" user "Package Geometry/Place Bound Top")
		(29 "B.CrtYd" user "Package Geometry/Place Bound Bottom")
		(35 "F.Fab" user "Ref Des/Assembly Top")
		(33 "B.Fab" user "Ref Des/Assembly Bottom")
	)
	(footprint ""
		(layer "F.Cu")
		(at 11.269472 -494.464848 180)
		(property "Reference" "PU3"
			(at 0 0 180)
			(layer "F.SilkS")
			(hide yes)
			(effects
				(font
					(size 1.27 1.27)
				)
			)
		)
		(property "Value" "TPS53319DQPR-GP"
			(at 4.7498 -5.6896 180)
			(unlocked yes)
			(layer "F.Fab")
			(hide yes)
			(effects
				(font
					(size 1.016 1.016)
					(thickness 0.1524)
				)
			)
		)
		(property "Device Type" "QFN22G6050-G6133H60"
			(at 4.7498 -7.2136 180)
			(unlocked yes)
			(layer "F.Fab")
			(hide yes)
			(effects
				(font
					(size 1.016 1.016)
					(thickness 0.1524)
				)
			)
		)
		(duplicate_pad_numbers_are_jumpers no)
		(fp_line
			(start 3.556 3.5179)
			(end 3.556 2.2479)
			(stroke
				(width 0.1524)
				(type default)
			)
			(layer "F.SilkS")
		)
		(fp_line
			(start 2.286 3.5179)
			(end 3.556 3.5179)
			(stroke
				(width 0.1524)
				(type default)
			)
			(layer "F.SilkS")
		)
		(fp_line
			(start 1.500124 3.262122)
			(end 1.500124 4.024122)
			(stroke
				(width 0.1524)
				(type default)
			)
			(layer "F.SilkS")
		)
		(fp_line
			(start 0.500126 -3.262122)
			(end 0.500126 -3.770122)
			(stroke
				(width 0.1524)
				(type default)
			)
			(layer "F.SilkS")
		)
		(fp_line
			(start -0.999998 3.262122)
			(end -0.999998 3.770122)
			(stroke
				(width 0.1524)
				(type default)
			)
			(layer "F.SilkS")
		)
		(fp_line
			(start -1.999996 -3.262122)
			(end -1.999996 -4.024122)
			(stroke
				(width 0.1524)
				(type default)
			)
			(layer "F.SilkS")
		)
		(fp_line
			(start -2.286 -3.5179)
			(end -3.556 -3.5179)
			(stroke
				(width 0.1524)
				(type default)
			)
			(layer "F.SilkS")
		)
		(fp_line
			(start -3.556 3.5179)
			(end -2.286 3.5179)
			(stroke
				(width 0.1524)
				(type default)
			)
			(layer "F.SilkS")
		)
		(fp_line
			(start -3.556 2.2479)
			(end -3.556 3.5179)
			(stroke
				(width 0.1524)
				(type default)
			)
			(layer "F.SilkS")
		)
		(fp_line
			(start -3.556 -3.5179)
			(end -3.556 -2.2479)
			(stroke
				(width 0.1524)
				(type default)
			)
			(layer "F.SilkS")
		)
		(fp_poly
			(pts
				(xy 3.556 -3.5179) (xy 2.5273 -3.5179) (xy 3.556 -2.4892)
			)
			(stroke
				(width 0)
				(type default)
			)
			(fill yes)
			(layer "F.SilkS")
		)
		(fp_rect
			(start -2.9972 2.5019)
			(end 2.9972 -2.5019)
			(stroke
				(width 0)
				(type default)
			)
			(fill no)
			(layer "F.CrtYd")
		)
		(fp_poly
			(pts
				(xy 3.556 -2.5019) (xy -2.9972 -2.5019) (xy -2.9972 2.5019) (xy 2.9972 2.5019) (xy 2.9972 -2.4892)
				(xy 3.556 -2.4892) (xy 3.556 3.5179) (xy -3.556 3.5179) (xy -3.556 -3.5179) (xy 3.556 -3.5179)
			)
			(stroke
				(width 0)
				(type default)
			)
			(fill no)
			(layer "F.CrtYd")
		)
		(fp_rect
			(start -3.556 3.5179)
			(end 3.556 -3.5179)
			(stroke
				(width 0)
				(type default)
			)
			(fill no)
			(layer "F.Fab")
		)
		(pad "1" smd rect
			(at 2.500122 -2.449322 180)
			(size 0.3048 1.1176)
			(layers "F.Cu" "F.Mask" "F.Paste")
			(net "P5VC_VFB")
		)
		(pad "2" smd rect
			(at 1.999996 -2.449322 180)
			(size 0.3048 1.1176)
			(layers "F.Cu" "F.Mask" "F.Paste")
			(net "P5VC_EN")
		)
		(pad "3" smd rect
			(at 1.500124 -2.449322 180)
			(size 0.3048 1.1176)
			(layers "F.Cu" "F.Mask" "F.Paste")
			(net "P5VC_PGD")
		)
		(pad "4" smd rect
			(at 0.999998 -2.449322 180)
			(size 0.3048 1.1176)
			(layers "F.Cu" "F.Mask" "F.Paste")
			(net "P5VC_VBST")
		)
		(pad "5" smd rect
			(at 0.500126 -2.449322 180)
			(size 0.3048 1.1176)
			(layers "F.Cu" "F.Mask" "F.Paste")
			(net "P5VC_ROVP")
		)
		(pad "6" smd rect
			(at 0 -2.449322 180)
			(size 0.3048 1.1176)
			(layers "F.Cu" "F.Mask" "F.Paste")
			(net "P5VC_LL")
		)
		(pad "7" smd rect
			(at -0.500126 -2.449322 180)
			(size 0.3048 1.1176)
			(layers "F.Cu" "F.Mask" "F.Paste")
			(net "P5VC_LL")
		)
		(pad "8" smd rect
			(at -0.999998 -2.449322 180)
			(size 0.3048 1.1176)
			(layers "F.Cu" "F.Mask" "F.Paste")
			(net "P5VC_LL")
		)
		(pad "9" smd rect
			(at -1.500124 -2.449322 180)
			(size 0.3048 1.1176)
			(layers "F.Cu" "F.Mask" "F.Paste")
			(net "P5VC_LL")
		)
		(pad "10" smd rect
			(at -1.999996 -2.449322 180)
			(size 0.3048 1.1176)
			(layers "F.Cu" "F.Mask" "F.Paste")
			(net "P5VC_LL")
		)
		(pad "11" smd rect
			(at -2.500122 -2.449322 180)
			(size 0.3048 1.1176)
			(layers "F.Cu" "F.Mask" "F.Paste")
			(net "P5VC_LL")
		)
		(pad "12" smd rect
			(at -2.500122 2.449322 180)
			(size 0.3048 1.1176)
			(layers "F.Cu" "F.Mask" "F.Paste")
			(net "P5VC_12VIN")
		)
		(pad "13" smd rect
			(at -1.999996 2.449322 180)
			(size 0.3048 1.1176)
			(layers "F.Cu" "F.Mask" "F.Paste")
			(net "P5VC_12VIN")
		)
		(pad "14" smd rect
			(at -1.500124 2.449322 180)
			(size 0.3048 1.1176)
			(layers "F.Cu" "F.Mask" "F.Paste")
			(net "P5VC_12VIN")
		)
		(pad "15" smd rect
			(at -0.999998 2.449322 180)
			(size 0.3048 1.1176)
			(layers "F.Cu" "F.Mask" "F.Paste")
			(net "P5VC_12VIN")
		)
		(pad "16" smd rect
			(at -0.500126 2.449322 180)
			(size 0.3048 1.1176)
			(layers "F.Cu" "F.Mask" "F.Paste")
			(net "P5VC_12VIN")
		)
		(pad "17" smd rect
			(at 0 2.449322 180)
			(size 0.3048 1.1176)
			(layers "F.Cu" "F.Mask" "F.Paste")
			(net "P5VC_12VIN")
		)
		(pad "18" smd rect
			(at 0.500126 2.449322 180)
			(size 0.3048 1.1176)
			(layers "F.Cu" "F.Mask" "F.Paste")
			(net "P5VC_VREG")
		)
		(pad "19" smd rect
			(at 0.999998 2.449322 180)
			(size 0.3048 1.1176)
			(layers "F.Cu" "F.Mask" "F.Paste")
			(net "P5VC_VDD")
		)
		(pad "20" smd rect
			(at 1.500124 2.449322 180)
			(size 0.3048 1.1176)
			(layers "F.Cu" "F.Mask" "F.Paste")
			(net "P5VC_MODE")
		)
		(pad "21" smd rect
			(at 1.999996 2.449322 180)
			(size 0.3048 1.1176)
			(layers "F.Cu" "F.Mask" "F.Paste")
			(net "P5VC_TRIP")
		)
		(pad "22" smd rect
			(at 2.500122 2.449322 180)
			(size 0.3048 1.1176)
			(layers "F.Cu" "F.Mask" "F.Paste")
			(net "P5VC_RF")
		)
		(pad "23" smd custom
			(at 0 0 180)
			(size 0.83185 0.83185)
			(layers "F.Cu" "F.Mask" "F.Paste")
			(net "GND")
			(options
				(clearance outline)
				(anchor circle)
			)
			(primitives
				(gr_poly
					(pts
						(xy -2.7813 1.6637) (xy -2.7813 1.2954) (xy -3.048 1.2954) (xy -3.048 0.9525) (xy -2.7813 0.9525)
						(xy -2.7813 -0.9525) (xy -3.048 -0.9525) (xy -3.048 -1.2954) (xy -2.7813 -1.2954) (xy -2.7813 -1.6637)
						(xy 2.7813 -1.6637) (xy 2.7813 -1.2954) (xy 3.048 -1.2954) (xy 3.048 -0.9525) (xy 2.7813 -0.9525)
						(xy 2.7813 0.9525) (xy 3.048 0.9525) (xy 3.048 1.2954) (xy 2.7813 1.2954) (xy 2.7813 1.6637)
					)
					(width 0)
					(fill yes)
				)
			)
		)
	)
	(footprint ""
		(layer "F.Cu")
		(at 83.692746 -395.6177 -90)
		(property "Reference" "R448"
			(at 0 0 270)
			(layer "F.SilkS")
			(hide yes)
			(effects
				(font
					(size 1.27 1.27)
				)
			)
		)
		(property "Value" "4K7R2J-2-GP"
			(at 0.064008 -3.993896 270)
			(unlocked yes)
			(layer "F.Fab")
			(hide yes)
			(effects
				(font
					(size 1.016 1.016)
					(thickness 0.1524)
				)
			)
		)
		(property "Device Type" "R402H16"
			(at 0.064008 -5.517896 270)
			(unlocked yes)
			(layer "F.Fab")
			(hide yes)
			(effects
				(font
					(size 1.016 1.016)
					(thickness 0.1524)
				)
			)
		)
		(duplicate_pad_numbers_are_jumpers no)
		(fp_line
			(start -0.508 -0.9398)
			(end -0.508 0.9398)
			(stroke
				(width 0.1524)
				(type default)
			)
			(layer "F.SilkS")
		)
		(fp_line
			(start 0.508 -0.9398)
			(end -0.508 -0.9398)
			(stroke
				(width 0.1524)
				(type default)
			)
			(layer "F.SilkS")
		)
		(fp_rect
			(start -0.508 0.9398)
			(end 0.508 -0.9398)
			(stroke
				(width 0)
				(type default)
			)
			(fill no)
			(layer "F.CrtYd")
		)
		(fp_rect
			(start -0.508 0.9398)
			(end 0.508 -0.9398)
			(stroke
				(width 0)
				(type default)
			)
			(fill no)
			(layer "F.Fab")
		)
		(pad "1" smd custom
			(at 0 -0.4445 270)
			(size 0.1397 0.1397)
			(layers "F.Cu" "F.Mask" "F.Paste")
			(net "P3V3")
			(options
				(clearance outline)
				(anchor circle)
			)
			(primitives
				(gr_poly
					(pts
						(arc
							(start -0.1778 -0.2794)
							(mid -0.249642 -0.249642)
							(end -0.2794 -0.1778)
						)
						(arc
							(start -0.2794 0.1778)
							(mid -0.249642 0.249642)
							(end -0.1778 0.2794)
						)
						(arc
							(start 0.1778 0.2794)
							(mid 0.249642 0.249642)
							(end 0.2794 0.1778)
						)
						(arc
							(start 0.2794 -0.1778)
							(mid 0.249642 -0.249642)
							(end 0.1778 -0.2794)
						)
					)
					(width 0)
					(fill yes)
				)
			)
		)
		(pad "2" smd custom
			(at 0 0.4445 270)
			(size 0.1397 0.1397)
			(layers "F.Cu" "F.Mask" "F.Paste")
			(net "SAS_EXP_A_PWR6")
			(options
				(clearance outline)
				(anchor circle)
			)
			(primitives
				(gr_poly
					(pts
						(arc
							(start -0.1778 -0.2794)
							(mid -0.249642 -0.249642)
							(end -0.2794 -0.1778)
						)
						(arc
							(start -0.2794 0.1778)
							(mid -0.249642 0.249642)
							(end -0.1778 0.2794)
						)
						(arc
							(start 0.1778 0.2794)
							(mid 0.249642 0.249642)
							(end 0.2794 0.1778)
						)
						(arc
							(start 0.2794 -0.1778)
							(mid 0.249642 -0.249642)
							(end 0.1778 -0.2794)
						)
					)
					(width 0)
					(fill yes)
				)
			)
		)
	)
	(footprint ""
		(layer "F.Cu")
		(at 242.569746 -18.5547 90)
		(property "Reference" "PC3"
			(at 0 0 90)
			(layer "F.SilkS")
			(hide yes)
			(effects
				(font
					(size 1.27 1.27)
				)
			)
		)
		(property "Value" "SC22U25V5MX-GP"
			(at -0.0762 -6.1214 90)
			(unlocked yes)
			(layer "F.Fab")
			(hide yes)
			(effects
				(font
					(size 1.016 1.016)
					(thickness 0.1524)
				)
			)
		)
		(property "Device Type" "C805H58"
			(at -0.0762 -8.1534 90)
			(unlocked yes)
			(layer "F.Fab")
			(hide yes)
			(effects
				(font
					(size 1.016 1.016)
					(thickness 0.1524)
				)
			)
		)
		(duplicate_pad_numbers_are_jumpers no)
		(fp_line
			(start 0.635 0)
			(end -0.635 0)
			(stroke
				(width 0.508)
				(type default)
			)
			(layer "F.SilkS")
		)
		(fp_rect
			(start -0.9652 1.778)
			(end 0.9652 -1.778)
			(stroke
				(width 0)
				(type default)
			)
			(fill no)
			(layer "F.CrtYd")
		)
		(fp_poly
			(pts
				(xy -0.9652 -1.778) (xy 0.9652 -1.778) (xy 0.9652 1.778) (xy -0.9652 1.778)
			)
			(stroke
				(width 0)
				(type default)
			)
			(fill no)
			(layer "F.Fab")
		)
		(pad "1" smd rect
			(at 0 -0.9652 90)
			(size 1.397 1.143)
			(layers "F.Cu" "F.Mask" "F.Paste")
			(net "P5VA_12VIN")
		)
		(pad "2" smd rect
			(at 0 0.9652 90)
			(size 1.397 1.143)
			(layers "F.Cu" "F.Mask" "F.Paste")
			(net "GND")
		)
	)
	(footprint ""
		(layer "F.Cu")
		(at 36.448746 -132.235702 180)
		(property "Reference" "R293"
			(at 0 0 180)
			(layer "F.SilkS")
			(hide yes)
			(effects
				(font
					(size 1.27 1.27)
				)
			)
		)
		(property "Value" "220R3F-1-GP"
			(at -0.0254 -2.5146 180)
			(unlocked yes)
			(layer "F.Fab")
			(hide yes)
			(effects
				(font
					(size 1.016 1.016)
					(thickness 0.1524)
				)
			)
		)
		(property "Device Type" "R603H22"
			(at -0.0254 -4.0386 180)
			(unlocked yes)
			(layer "F.Fab")
			(hide yes)
			(effects
				(font
					(size 1.016 1.016)
					(thickness 0.1524)
				)
			)
		)
		(duplicate_pad_numbers_are_jumpers no)
		(fp_line
			(start 0.2032 0)
			(end 0.4826 0)
			(stroke
				(width 0.2032)
				(type default)
			)
			(layer "F.SilkS")
		)
		(fp_line
			(start -0.4826 0)
			(end -0.2032 0)
			(stroke
				(width 0.2032)
				(type default)
			)
			(layer "F.SilkS")
		)
		(fp_rect
			(start -0.5842 1.3335)
			(end 0.5842 -1.3335)
			(stroke
				(width 0)
				(type default)
			)
			(fill no)
			(layer "F.CrtYd")
		)
		(fp_rect
			(start -0.5842 1.3335)
			(end 0.5842 -1.3335)
			(stroke
				(width 0)
				(type default)
			)
			(fill no)
			(layer "F.Fab")
		)
		(pad "1" smd custom
			(at 0 -0.762 180)
			(size 0.2159 0.2159)
			(layers "F.Cu" "F.Mask" "F.Paste")
			(net "HDD_PRSNT_NET13")
			(options
				(clearance outline)
				(anchor circle)
			)
			(primitives
				(gr_poly
					(pts
						(arc
							(start -0.3302 -0.4318)
							(mid -0.402042 -0.402042)
							(end -0.4318 -0.3302)
						)
						(arc
							(start -0.4318 0.3302)
							(mid -0.402042 0.402042)
							(end -0.3302 0.4318)
						)
						(arc
							(start 0.3302 0.4318)
							(mid 0.402042 0.402042)
							(end 0.4318 0.3302)
						)
						(arc
							(start 0.4318 -0.3302)
							(mid 0.402042 -0.402042)
							(end 0.3302 -0.4318)
						)
					)
					(width 0)
					(fill yes)
				)
			)
		)
		(pad "2" smd custom
			(at 0 0.762 180)
			(size 0.2159 0.2159)
			(layers "F.Cu" "F.Mask" "F.Paste")
			(net "HDD_PRSNT13")
			(options
				(clearance outline)
				(anchor circle)
			)
			(primitives
				(gr_poly
					(pts
						(arc
							(start -0.3302 -0.4318)
							(mid -0.402042 -0.402042)
							(end -0.4318 -0.3302)
						)
						(arc
							(start -0.4318 0.3302)
							(mid -0.402042 0.402042)
							(end -0.3302 0.4318)
						)
						(arc
							(start 0.3302 0.4318)
							(mid 0.402042 0.402042)
							(end 0.4318 0.3302)
						)
						(arc
							(start 0.4318 -0.3302)
							(mid 0.402042 -0.402042)
							(end 0.3302 -0.4318)
						)
					)
					(width 0)
					(fill yes)
				)
			)
		)
	)
	(footprint ""
		(layer "F.Cu")
		(at 26.288746 -442.7347 90)
		(property "Reference" "C264"
			(at 0 0 90)
			(layer "F.SilkS")
			(hide yes)
			(effects
				(font
					(size 1.27 1.27)
				)
			)
		)
		(property "Value" "SCD01U50V2KX-1GP"
			(at 1.1811 -2.7051 90)
			(unlocked yes)
			(layer "F.Fab")
			(hide yes)
			(effects
				(font
					(size 1.016 1.016)
					(thickness 0.1524)
				)
			)
		)
		(property "Device Type" "C402H22"
			(at 1.1811 -4.2291 90)
			(unlocked yes)
			(layer "F.Fab")
			(hide yes)
			(effects
				(font
					(size 1.016 1.016)
					(thickness 0.1524)
				)
			)
		)
		(duplicate_pad_numbers_are_jumpers no)
		(fp_rect
			(start -0.4318 0.9525)
			(end 0.4318 -0.9525)
			(stroke
				(width 0)
				(type default)
			)
			(fill no)
			(layer "F.CrtYd")
		)
		(fp_rect
			(start -0.4318 0.9525)
			(end 0.4318 -0.9525)
			(stroke
				(width 0)
				(type default)
			)
			(fill no)
			(layer "F.Fab")
		)
		(pad "1" smd custom
			(at 0 -0.4445 90)
			(size 0.1524 0.1524)
			(layers "F.Cu" "F.Mask" "F.Paste")
			(net "SAS2X28_DRIVE_RX_N_B10")
			(options
				(clearance outline)
				(anchor circle)
			)
			(primitives
				(gr_poly
					(pts
						(arc
							(start 0.3048 -0.2032)
							(mid 0.275042 -0.275042)
							(end 0.2032 -0.3048)
						)
						(arc
							(start -0.2032 -0.3048)
							(mid -0.275042 -0.275042)
							(end -0.3048 -0.2032)
						)
						(arc
							(start -0.3048 0.2032)
							(mid -0.275042 0.275042)
							(end -0.2032 0.3048)
						)
						(arc
							(start 0.2032 0.3048)
							(mid 0.275042 0.275042)
							(end 0.3048 0.2032)
						)
					)
					(width 0)
					(fill yes)
				)
			)
		)
		(pad "2" smd custom
			(at 0 0.4445 90)
			(size 0.1524 0.1524)
			(layers "F.Cu" "F.Mask" "F.Paste")
			(net "SAS2X28_B_HDD10_RX_-")
			(options
				(clearance outline)
				(anchor circle)
			)
			(primitives
				(gr_poly
					(pts
						(arc
							(start 0.3048 -0.2032)
							(mid 0.275042 -0.275042)
							(end 0.2032 -0.3048)
						)
						(arc
							(start -0.2032 -0.3048)
							(mid -0.275042 -0.275042)
							(end -0.3048 -0.2032)
						)
						(arc
							(start -0.3048 0.2032)
							(mid -0.275042 0.275042)
							(end -0.2032 0.3048)
						)
						(arc
							(start 0.2032 0.3048)
							(mid 0.275042 0.275042)
							(end 0.3048 0.2032)
						)
					)
					(width 0)
					(fill yes)
				)
			)
		)
	)
	(footprint ""
		(layer "F.Cu")
		(at 45.783246 -124.041662 90)
		(property "Reference" "U40"
			(at 0 0 90)
			(layer "F.SilkS")
			(hide yes)
			(effects
				(font
					(size 1.27 1.27)
				)
			)
		)
		(property "Value" "74LVC1G08GW-1-GP"
			(at -2.3368 -8.6868 90)
			(unlocked yes)
			(layer "F.Fab")
			(hide yes)
			(effects
				(font
					(size 1.016 1.016)
					(thickness 0.1524)
				)
			)
		)
		(property "Device Type" "SC70-5H44"
			(at -2.3114 -10.414 90)
			(unlocked yes)
			(layer "F.Fab")
			(hide yes)
			(effects
				(font
					(size 1.016 1.016)
					(thickness 0.1524)
				)
			)
		)
		(duplicate_pad_numbers_are_jumpers no)
		(fp_line
			(start 1.3843 -1.8034)
			(end 1.3843 -1.1176)
			(stroke
				(width 0.3302)
				(type default)
			)
			(layer "F.SilkS")
		)
		(fp_line
			(start 0.6604 -1.8034)
			(end 1.3843 -1.8034)
			(stroke
				(width 0.3302)
				(type default)
			)
			(layer "F.SilkS")
		)
		(fp_line
			(start 1.27 -1.7018)
			(end 1.27 1.7018)
			(stroke
				(width 0.1524)
				(type default)
			)
			(layer "F.SilkS")
		)
		(fp_line
			(start -1.27 -1.7018)
			(end 1.27 -1.7018)
			(stroke
				(width 0.1524)
				(type default)
			)
			(layer "F.SilkS")
		)
		(fp_line
			(start 1.27 1.7018)
			(end -1.27 1.7018)
			(stroke
				(width 0.1524)
				(type default)
			)
			(layer "F.SilkS")
		)
		(fp_line
			(start -1.27 1.7018)
			(end -1.27 -1.7018)
			(stroke
				(width 0.1524)
				(type default)
			)
			(layer "F.SilkS")
		)
		(fp_rect
			(start -1.524 1.9558)
			(end 1.524 -1.9558)
			(stroke
				(width 0)
				(type default)
			)
			(fill no)
			(layer "F.CrtYd")
		)
		(fp_poly
			(pts
				(xy -1.524 -1.9558) (xy 1.524 -1.9558) (xy 1.524 1.9558) (xy -1.524 1.9558)
			)
			(stroke
				(width 0)
				(type default)
			)
			(fill no)
			(layer "F.Fab")
		)
		(pad "1" smd rect
			(at 0.65024 -0.8255 90)
			(size 0.4064 1.2192)
			(layers "F.Cu" "F.Mask" "F.Paste")
			(net "SAS2X28_B_HDD13_FLT")
		)
		(pad "2" smd rect
			(at 0 -0.8255 90)
			(size 0.4064 1.2192)
			(layers "F.Cu" "F.Mask" "F.Paste")
			(net "SAS2X28_A_HDD13_FLT")
		)
		(pad "3" smd rect
			(at -0.65024 -0.8255 90)
			(size 0.4064 1.2192)
			(layers "F.Cu" "F.Mask" "F.Paste")
			(net "GND")
		)
		(pad "4" smd rect
			(at -0.65024 0.8255 90)
			(size 0.4064 1.2192)
			(layers "F.Cu" "F.Mask" "F.Paste")
			(net "FLT_HDD13_DRIVE")
		)
		(pad "5" smd rect
			(at 0.65024 0.8255 90)
			(size 0.4064 1.2192)
			(layers "F.Cu" "F.Mask" "F.Paste")
			(net "P3V3")
		)
	)
)
